# T6G (Grand Teton) — schematic netlist excerpt (pin names and nets, part order shuffled) for the footprints in the layout excerpt that follows; sources: Cadence DE-HDL packaged netlist, KiCad conversion of 04192023_DAF0TMB3IC0_F0TG_MB_C_brd_V02_OCP.brd

R5071  Q_RES  100 1% CHIP  pkg 0402LF  page 167 : A = P1V8_AUX ; B = FM_FORCE_ALL_PWRON_ON

Q125  MOSFET_NCH_DUAL  PJT138K IC  pkg SOT363XD  page 152
  S1  = GND
  G1  = P12V_SCM_EN_R
  D2  = P12V_SCM_UV_R
  S2  = GND
  G2  = P12V_SCM_EN_G
  D1  = P12V_SCM_EN_G

(kicad_pcb
	(version 20260206)
	(generator "pcbnew")
	(generator_version "10.0")
	(general
		(thickness 1.6)
		(legacy_teardrops no)
	)
	(paper "A4")
	(title_block
		(title "04192023_DAF0TMB3IC0_F0TG_MB_C_brd_V02_OCP.brd")
		(comment 1 "Grand Teton / footprints 4361-4362 of 8354")
	)
	(layers
		(0 "F.Cu" signal "TOP")
		(4 "In1.Cu" signal "GND")
		(6 "In2.Cu" signal "IN1")
		(8 "In3.Cu" signal "GND1")
		(10 "In4.Cu" signal "IN2")
		(12 "In5.Cu" signal "GND2")
		(14 "In6.Cu" signal "IN3")
		(16 "In7.Cu" signal "GND3")
		(18 "In8.Cu" signal "VCC")
		(20 "In9.Cu" signal "VCC1")
		(22 "In10.Cu" signal "GND4")
		(24 "In11.Cu" signal "IN4")
		(26 "In12.Cu" signal "GND5")
		(28 "In13.Cu" signal "IN5")
		(30 "In14.Cu" signal "GND6")
		(32 "In15.Cu" signal "IN6")
		(34 "In16.Cu" signal "GND7")
		(2 "B.Cu" signal "BOTTOM")
		(9 "F.Adhes" user "F.Adhesive")
		(11 "B.Adhes" user "B.Adhesive")
		(13 "F.Paste" user "Package Geometry/Pastemask Top")
		(15 "B.Paste" user "Package Geometry/Pastemask Bottom")
		(5 "F.SilkS" user "Ref Des/Silkscreen Top")
		(7 "B.SilkS" user "Ref Des/Silkscreen Bottom")
		(1 "F.Mask" user "Board Geometry/Soldermask Top")
		(3 "B.Mask" user "Board Geometry/Soldermask Bottom")
		(17 "Dwgs.User" user "User.Drawings")
		(19 "Cmts.User" user "User.Comments")
		(21 "Eco1.User" user "User.Eco1")
		(23 "Eco2.User" user "User.Eco2")
		(25 "Edge.Cuts" user "Board Geometry/Outline")
		(27 "Margin" user)
		(31 "F.CrtYd" user "Package Geometry/Place Bound Top")
		(29 "B.CrtYd" user "Package Geometry/Place Bound Bottom")
		(35 "F.Fab" user "Ref Des/Assembly Top")
		(33 "B.Fab" user "Ref Des/Assembly Bottom")
	)
	(footprint ""
		(layer "F.Cu")
		(at 194.30619 -43.199558 180)
		(property "Reference" "Q125"
			(at 1.7526 1.856232 0)
			(unlocked yes)
			(layer "F.SilkS")
			(effects
				(font
					(size 0.7874 0.5842)
					(thickness 0.1524)
				)
				(justify left)
			)
		)
		(property "Value" ""
			(at 0 0 180)
			(layer "F.Fab")
			(effects
				(font
					(size 1.27 1.27)
				)
			)
		)
		(duplicate_pad_numbers_are_jumpers no)
		(fp_line
			(start 1.332738 1.100074)
			(end -1.332738 1.100074)
			(stroke
				(width 0.1524)
				(type default)
			)
			(layer "F.SilkS")
		)
		(fp_line
			(start 1.332738 -1.100074)
			(end 1.332738 1.100074)
			(stroke
				(width 0.1524)
				(type default)
			)
			(layer "F.SilkS")
		)
		(fp_line
			(start 0.4826 -1.100074)
			(end 1.332738 -1.100074)
			(stroke
				(width 0.1524)
				(type default)
			)
			(layer "F.SilkS")
		)
		(fp_line
			(start 0 -0.541274)
			(end 0.4826 -1.100074)
			(stroke
				(width 0.1524)
				(type default)
			)
			(layer "F.SilkS")
		)
		(fp_line
			(start -0.4826 -1.100074)
			(end 0 -0.541274)
			(stroke
				(width 0.1524)
				(type default)
			)
			(layer "F.SilkS")
		)
		(fp_line
			(start -1.332738 1.100074)
			(end -1.332738 -1.100074)
			(stroke
				(width 0.1524)
				(type default)
			)
			(layer "F.SilkS")
		)
		(fp_line
			(start -1.332738 -1.100074)
			(end -0.4826 -1.100074)
			(stroke
				(width 0.1524)
				(type default)
			)
			(layer "F.SilkS")
		)
		(fp_poly
			(pts
				(xy -1.980438 -0.69215) (xy -2.682494 -0.341122) (xy -2.682494 -1.043178)
			)
			(stroke
				(width 0)
				(type default)
			)
			(fill yes)
			(layer "F.SilkS")
		)
		(fp_line
			(start 0.674878 1.100074)
			(end -0.674878 1.100074)
			(stroke
				(width 0.1)
				(type default)
			)
			(layer "F.Fab")
		)
		(fp_line
			(start 0.674878 -1.100074)
			(end 0.674878 1.100074)
			(stroke
				(width 0.1)
				(type default)
			)
			(layer "F.Fab")
		)
		(fp_line
			(start -0.674878 1.100074)
			(end -0.674878 -1.100074)
			(stroke
				(width 0.1)
				(type default)
			)
			(layer "F.Fab")
		)
		(fp_line
			(start -0.674878 -1.100074)
			(end 0.674878 -1.100074)
			(stroke
				(width 0.1)
				(type default)
			)
			(layer "F.Fab")
		)
		(fp_poly
			(pts
				(xy -2.2352 -0.298958) (xy -2.2352 -1.001014) (xy -1.533144 -0.649986)
			)
			(stroke
				(width 0)
				(type default)
			)
			(fill yes)
			(layer "F.Fab")
		)
		(pad "1" smd rect
			(at -0.94996 -0.649986 270)
			(size 0.4318 0.508)
			(layers "F.Cu" "F.Mask" "F.Paste")
			(net "GND")
		)
		(pad "2" smd rect
			(at -0.94996 0 270)
			(size 0.4318 0.508)
			(layers "F.Cu" "F.Mask" "F.Paste")
			(net "P12V_SCM_EN_R")
		)
		(pad "3" smd rect
			(at -0.94996 0.649986 270)
			(size 0.4318 0.508)
			(layers "F.Cu" "F.Mask" "F.Paste")
			(net "P12V_SCM_UV_R")
		)
		(pad "4" smd rect
			(at 0.94996 0.649986 270)
			(size 0.4318 0.508)
			(layers "F.Cu" "F.Mask" "F.Paste")
			(net "GND")
		)
		(pad "5" smd rect
			(at 0.94996 0 270)
			(size 0.4318 0.508)
			(layers "F.Cu" "F.Mask" "F.Paste")
			(net "P12V_SCM_EN_G")
		)
		(pad "6" smd rect
			(at 0.94996 -0.649986 270)
			(size 0.4318 0.508)
			(layers "F.Cu" "F.Mask" "F.Paste")
			(net "P12V_SCM_EN_G")
		)
	)
	(footprint ""
		(layer "F.Cu")
		(at 420.75735 -41.087548)
		(property "Reference" "R5071"
			(at 0 0 0)
			(layer "F.SilkS")
			(hide yes)
			(effects
				(font
					(size 1.27 1.27)
				)
			)
		)
		(property "Value" ""
			(at 0 0 0)
			(layer "F.Fab")
			(effects
				(font
					(size 1.27 1.27)
				)
			)
		)
		(duplicate_pad_numbers_are_jumpers no)
		(fp_line
			(start -0.7874 -0.4064)
			(end 0.7874 -0.4064)
			(stroke
				(width 0.1524)
				(type default)
			)
			(layer "F.SilkS")
		)
		(fp_line
			(start -0.7874 0.4064)
			(end -0.7874 -0.4064)
			(stroke
				(width 0.1524)
				(type default)
			)
			(layer "F.SilkS")
		)
		(fp_line
			(start 0.7874 -0.4064)
			(end 0.7874 0.4064)
			(stroke
				(width 0.1524)
				(type default)
			)
			(layer "F.SilkS")
		)
		(fp_line
			(start 0.7874 0.4064)
			(end -0.7874 0.4064)
			(stroke
				(width 0.1524)
				(type default)
			)
			(layer "F.SilkS")
		)
		(fp_line
			(start -0.67945 -0.305054)
			(end -0.12065 -0.305054)
			(stroke
				(width 0.1)
				(type default)
			)
			(layer "F.Fab")
		)
		(fp_line
			(start -0.67945 0.3048)
			(end -0.67945 -0.305054)
			(stroke
				(width 0.1)
				(type default)
			)
			(layer "F.Fab")
		)
		(fp_line
			(start -0.12065 -0.305054)
			(end -0.12065 -0.2794)
			(stroke
				(width 0.1)
				(type default)
			)
			(layer "F.Fab")
		)
		(fp_line
			(start -0.12065 -0.2794)
			(end 0.12065 -0.2794)
			(stroke
				(width 0.1)
				(type default)
			)
			(layer "F.Fab")
		)
		(fp_line
			(start -0.12065 0.2794)
			(end -0.12065 0.3048)
			(stroke
				(width 0.1)
				(type default)
			)
			(layer "F.Fab")
		)
		(fp_line
			(start -0.12065 0.3048)
			(end -0.67945 0.3048)
			(stroke
				(width 0.1)
				(type default)
			)
			(layer "F.Fab")
		)
		(fp_line
			(start 0.120396 0.2794)
			(end -0.12065 0.2794)
			(stroke
				(width 0.1)
				(type default)
			)
			(layer "F.Fab")
		)
		(fp_line
			(start 0.120396 0.3048)
			(end 0.120396 0.2794)
			(stroke
				(width 0.1)
				(type default)
			)
			(layer "F.Fab")
		)
		(fp_line
			(start 0.12065 -0.3048)
			(end 0.67945 -0.3048)
			(stroke
				(width 0.1)
				(type default)
			)
			(layer "F.Fab")
		)
		(fp_line
			(start 0.12065 -0.2794)
			(end 0.12065 -0.3048)
			(stroke
				(width 0.1)
				(type default)
			)
			(layer "F.Fab")
		)
		(fp_line
			(start 0.67945 -0.3048)
			(end 0.67945 0.3048)
			(stroke
				(width 0.1)
				(type default)
			)
			(layer "F.Fab")
		)
		(fp_line
			(start 0.67945 0.3048)
			(end 0.120396 0.3048)
			(stroke
				(width 0.1)
				(type default)
			)
			(layer "F.Fab")
		)
		(pad "1" smd circle
			(at -0.40005 0)
			(size 0 0)
			(layers "F.Cu" "F.Mask" "F.Paste")
			(net "P1V8_AUX")
		)
		(pad "2" smd circle
			(at 0.40005 0)
			(size 0 0)
			(layers "F.Cu" "F.Mask" "F.Paste")
			(net "FM_FORCE_ALL_PWRON_ON")
		)
	)
)
